# S9S_MB_2U (Grand Teton) — schematic netlist excerpt (pin names and nets, part order shuffled) for the footprints in the layout excerpt that follows; sources: Cadence DE-HDL packaged netlist, KiCad conversion of 03242023_DA0F0TMBIJ0_F0T_Motherboard_J_brd_V01_OCP.brd

R666  Q_RES  0 5% EMPTY  pkg 0402LF  page 230 : A = I3C_SPD_DDRABCD_CPU1_R_SDA ; B = I3C_SPD_DDRABCD_CPU1_LVC1_R_SDA
R448  Q_RES  0 5% EMPTY  pkg 0402LF  page 236 : A = SMB_S3M_CPU0_3V3AUX_SCL ; B = SMB_S3M_CPU1_3V3AUX_SCL

(kicad_pcb
	(version 20260206)
	(generator "pcbnew")
	(generator_version "10.0")
	(general
		(thickness 1.6)
		(legacy_teardrops no)
	)
	(paper "A4")
	(title_block
		(title "03242023_DA0F0TMBIJ0_F0T_Motherboard_J_brd_V01_OCP.brd")
		(comment 1 "Grand Teton / footprints 1264-1265 of 6105")
	)
	(layers
		(0 "F.Cu" signal "TOP")
		(4 "In1.Cu" signal "GND")
		(6 "In2.Cu" signal "IN1")
		(8 "In3.Cu" signal "GND1")
		(10 "In4.Cu" signal "IN2")
		(12 "In5.Cu" signal "GND2")
		(14 "In6.Cu" signal "IN3")
		(16 "In7.Cu" signal "GND3")
		(18 "In8.Cu" signal "VCC")
		(20 "In9.Cu" signal "VCC1")
		(22 "In10.Cu" signal "GND4")
		(24 "In11.Cu" signal "IN4")
		(26 "In12.Cu" signal "GND5")
		(28 "In13.Cu" signal "IN5")
		(30 "In14.Cu" signal "GND6")
		(32 "In15.Cu" signal "IN6")
		(34 "In16.Cu" signal "GND7")
		(2 "B.Cu" signal "BOTTOM")
		(9 "F.Adhes" user "F.Adhesive")
		(11 "B.Adhes" user "B.Adhesive")
		(13 "F.Paste" user "Package Geometry/Pastemask Top")
		(15 "B.Paste" user "Package Geometry/Pastemask Bottom")
		(5 "F.SilkS" user "Ref Des/Silkscreen Top")
		(7 "B.SilkS" user "Ref Des/Silkscreen Bottom")
		(1 "F.Mask" user "Board Geometry/Soldermask Top")
		(3 "B.Mask" user "Board Geometry/Soldermask Bottom")
		(17 "Dwgs.User" user "User.Drawings")
		(19 "Cmts.User" user "User.Comments")
		(21 "Eco1.User" user "User.Eco1")
		(23 "Eco2.User" user "User.Eco2")
		(25 "Edge.Cuts" user "Board Geometry/Outline")
		(27 "Margin" user)
		(31 "F.CrtYd" user "Package Geometry/Place Bound Top")
		(29 "B.CrtYd" user "Package Geometry/Place Bound Bottom")
		(35 "F.Fab" user "Ref Des/Assembly Top")
		(33 "B.Fab" user "Ref Des/Assembly Bottom")
	)
	(footprint ""
		(layer "F.Cu")
		(at 77.966824 -142.587218 90)
		(property "Reference" "R666"
			(at 0 0 90)
			(layer "F.SilkS")
			(hide yes)
			(effects
				(font
					(size 1.27 1.27)
				)
			)
		)
		(property "Value" ""
			(at 0 0 90)
			(layer "F.Fab")
			(effects
				(font
					(size 1.27 1.27)
				)
			)
		)
		(duplicate_pad_numbers_are_jumpers no)
		(fp_line
			(start 0.7874 -0.4064)
			(end 0.7874 0.4064)
			(stroke
				(width 0.1524)
				(type default)
			)
			(layer "F.SilkS")
		)
		(fp_line
			(start -0.7874 -0.4064)
			(end 0.7874 -0.4064)
			(stroke
				(width 0.1524)
				(type default)
			)
			(layer "F.SilkS")
		)
		(fp_line
			(start 0.7874 0.4064)
			(end -0.7874 0.4064)
			(stroke
				(width 0.1524)
				(type default)
			)
			(layer "F.SilkS")
		)
		(fp_line
			(start -0.7874 0.4064)
			(end -0.7874 -0.4064)
			(stroke
				(width 0.1524)
				(type default)
			)
			(layer "F.SilkS")
		)
		(fp_line
			(start -0.12065 -0.305054)
			(end -0.12065 -0.2794)
			(stroke
				(width 0.1)
				(type default)
			)
			(layer "F.Fab")
		)
		(fp_line
			(start -0.67945 -0.305054)
			(end -0.12065 -0.305054)
			(stroke
				(width 0.1)
				(type default)
			)
			(layer "F.Fab")
		)
		(fp_line
			(start 0.67945 -0.3048)
			(end 0.67945 0.3048)
			(stroke
				(width 0.1)
				(type default)
			)
			(layer "F.Fab")
		)
		(fp_line
			(start 0.12065 -0.3048)
			(end 0.67945 -0.3048)
			(stroke
				(width 0.1)
				(type default)
			)
			(layer "F.Fab")
		)
		(fp_line
			(start 0.12065 -0.2794)
			(end 0.12065 -0.3048)
			(stroke
				(width 0.1)
				(type default)
			)
			(layer "F.Fab")
		)
		(fp_line
			(start -0.12065 -0.2794)
			(end 0.12065 -0.2794)
			(stroke
				(width 0.1)
				(type default)
			)
			(layer "F.Fab")
		)
		(fp_line
			(start 0.120396 0.2794)
			(end -0.12065 0.2794)
			(stroke
				(width 0.1)
				(type default)
			)
			(layer "F.Fab")
		)
		(fp_line
			(start -0.12065 0.2794)
			(end -0.12065 0.3048)
			(stroke
				(width 0.1)
				(type default)
			)
			(layer "F.Fab")
		)
		(fp_line
			(start 0.67945 0.3048)
			(end 0.120396 0.3048)
			(stroke
				(width 0.1)
				(type default)
			)
			(layer "F.Fab")
		)
		(fp_line
			(start 0.120396 0.3048)
			(end 0.120396 0.2794)
			(stroke
				(width 0.1)
				(type default)
			)
			(layer "F.Fab")
		)
		(fp_line
			(start -0.12065 0.3048)
			(end -0.67945 0.3048)
			(stroke
				(width 0.1)
				(type default)
			)
			(layer "F.Fab")
		)
		(fp_line
			(start -0.67945 0.3048)
			(end -0.67945 -0.305054)
			(stroke
				(width 0.1)
				(type default)
			)
			(layer "F.Fab")
		)
		(pad "1" smd circle
			(at -0.40005 0 90)
			(size 0 0)
			(layers "F.Cu" "F.Mask" "F.Paste")
			(net "I3C_SPD_DDRABCD_CPU1_R_SDA")
		)
		(pad "2" smd circle
			(at 0.40005 0 90)
			(size 0 0)
			(layers "F.Cu" "F.Mask" "F.Paste")
			(net "I3C_SPD_DDRABCD_CPU1_LVC1_R_SDA")
		)
	)
	(footprint ""
		(layer "F.Cu")
		(at 394.39088 -148.808948 -90)
		(property "Reference" "R448"
			(at 0 0 270)
			(layer "F.SilkS")
			(hide yes)
			(effects
				(font
					(size 1.27 1.27)
				)
			)
		)
		(property "Value" ""
			(at 0 0 270)
			(layer "F.Fab")
			(effects
				(font
					(size 1.27 1.27)
				)
			)
		)
		(duplicate_pad_numbers_are_jumpers no)
		(fp_line
			(start -0.7874 0.4064)
			(end -0.7874 -0.4064)
			(stroke
				(width 0.1524)
				(type default)
			)
			(layer "F.SilkS")
		)
		(fp_line
			(start 0.7874 0.4064)
			(end -0.7874 0.4064)
			(stroke
				(width 0.1524)
				(type default)
			)
			(layer "F.SilkS")
		)
		(fp_line
			(start -0.7874 -0.4064)
			(end 0.7874 -0.4064)
			(stroke
				(width 0.1524)
				(type default)
			)
			(layer "F.SilkS")
		)
		(fp_line
			(start 0.7874 -0.4064)
			(end 0.7874 0.4064)
			(stroke
				(width 0.1524)
				(type default)
			)
			(layer "F.SilkS")
		)
		(fp_line
			(start -0.67945 0.3048)
			(end -0.67945 -0.305054)
			(stroke
				(width 0.1)
				(type default)
			)
			(layer "F.Fab")
		)
		(fp_line
			(start -0.12065 0.3048)
			(end -0.67945 0.3048)
			(stroke
				(width 0.1)
				(type default)
			)
			(layer "F.Fab")
		)
		(fp_line
			(start 0.120396 0.3048)
			(end 0.120396 0.2794)
			(stroke
				(width 0.1)
				(type default)
			)
			(layer "F.Fab")
		)
		(fp_line
			(start 0.67945 0.3048)
			(end 0.120396 0.3048)
			(stroke
				(width 0.1)
				(type default)
			)
			(layer "F.Fab")
		)
		(fp_line
			(start -0.12065 0.2794)
			(end -0.12065 0.3048)
			(stroke
				(width 0.1)
				(type default)
			)
			(layer "F.Fab")
		)
		(fp_line
			(start 0.120396 0.2794)
			(end -0.12065 0.2794)
			(stroke
				(width 0.1)
				(type default)
			)
			(layer "F.Fab")
		)
		(fp_line
			(start -0.12065 -0.2794)
			(end 0.12065 -0.2794)
			(stroke
				(width 0.1)
				(type default)
			)
			(layer "F.Fab")
		)
		(fp_line
			(start 0.12065 -0.2794)
			(end 0.12065 -0.3048)
			(stroke
				(width 0.1)
				(type default)
			)
			(layer "F.Fab")
		)
		(fp_line
			(start 0.12065 -0.3048)
			(end 0.67945 -0.3048)
			(stroke
				(width 0.1)
				(type default)
			)
			(layer "F.Fab")
		)
		(fp_line
			(start 0.67945 -0.3048)
			(end 0.67945 0.3048)
			(stroke
				(width 0.1)
				(type default)
			)
			(layer "F.Fab")
		)
		(fp_line
			(start -0.67945 -0.305054)
			(end -0.12065 -0.305054)
			(stroke
				(width 0.1)
				(type default)
			)
			(layer "F.Fab")
		)
		(fp_line
			(start -0.12065 -0.305054)
			(end -0.12065 -0.2794)
			(stroke
				(width 0.1)
				(type default)
			)
			(layer "F.Fab")
		)
		(pad "1" smd circle
			(at -0.40005 0 270)
			(size 0 0)
			(layers "F.Cu" "F.Mask" "F.Paste")
			(net "SMB_S3M_CPU0_3V3AUX_SCL")
		)
		(pad "2" smd circle
			(at 0.40005 0 270)
			(size 0 0)
			(layers "F.Cu" "F.Mask" "F.Paste")
			(net "SMB_S3M_CPU1_3V3AUX_SCL")
		)
	)
)
